(kicad_pcb
	(version 20241229)
	(generator "pcbnew")
	(generator_version "9.0")
	(general
		(thickness 1.552)
		(legacy_teardrops no)
	)
	(paper "A4")
	(title_block
		(date "2023-07-25")
		(rev "1.1.4")
		(comment 9 "footprints 137-138 of 379")
	)
	(layers
		(0 "F.Cu" signal)
		(4 "In1.Cu" signal)
		(6 "In2.Cu" signal)
		(8 "In3.Cu" signal)
		(10 "In4.Cu" signal)
		(12 "In5.Cu" signal)
		(14 "In6.Cu" signal)
		(2 "B.Cu" signal)
		(9 "F.Adhes" user "F.Adhesive")
		(11 "B.Adhes" user "B.Adhesive")
		(13 "F.Paste" user)
		(15 "B.Paste" user)
		(5 "F.SilkS" user "F.Silkscreen")
		(7 "B.SilkS" user "B.Silkscreen")
		(1 "F.Mask" user)
		(3 "B.Mask" user)
		(17 "Dwgs.User" user "User.Drawings")
		(19 "Cmts.User" user "User.Comments")
		(21 "Eco1.User" user "User.Eco1")
		(23 "Eco2.User" user "User.Eco2")
		(25 "Edge.Cuts" user)
		(27 "Margin" user)
		(31 "F.CrtYd" user "F.Courtyard")
		(29 "B.CrtYd" user "B.Courtyard")
		(35 "F.Fab" user)
		(33 "B.Fab" user)
	)
	(footprint "antmicro-footprints:Conn_FFC_WE_68715014x22"
		(layer "F.Cu")
		(at 124.93 122.27)
		(property "Reference" "J6"
			(at 0 -3.4 0)
			(layer "F.SilkS")
			(effects
				(font
					(size 0.65 0.65)
					(thickness 0.15)
				)
				(justify left bottom)
			)
		)
		(property "Value" "Conn_FFC_WE_68715014522_ONE-SIDE"
			(at 0 4.5 0)
			(layer "F.Fab")
			(hide yes)
			(effects
				(font
					(size 0.7 0.7)
					(thickness 0.15)
				)
				(justify left bottom)
			)
		)
		(property "Datasheet" "https://www.we-online.com/components/products/datasheet/68715014522.pdf"
			(at 0 0 0)
			(layer "F.Fab")
			(hide yes)
			(effects
				(font
					(size 1.27 1.27)
					(thickness 0.15)
				)
			)
		)
		(property "Description" "FFC connector"
			(at 0 0 0)
			(layer "F.Fab")
			(hide yes)
			(effects
				(font
					(size 1.27 1.27)
					(thickness 0.15)
				)
			)
		)
		(property "Author" "Antmicro"
			(at 0 0 0)
			(layer "F.Fab")
			(hide yes)
			(effects
				(font
					(size 1 1)
					(thickness 0.15)
				)
			)
		)
		(property "License" "Apache-2.0"
			(at 0 0 0)
			(layer "F.Fab")
			(hide yes)
			(effects
				(font
					(size 1 1)
					(thickness 0.15)
				)
			)
		)
		(property "MPN" "68715014522"
			(at 0 0 0)
			(layer "F.Fab")
			(hide yes)
			(effects
				(font
					(size 1 1)
					(thickness 0.15)
				)
			)
		)
		(property "Manufacturer" "Würth Elektronik"
			(at 0 0 0)
			(layer "F.Fab")
			(hide yes)
			(effects
				(font
					(size 1 1)
					(thickness 0.15)
				)
			)
		)
		(sheetname "/Peripherals/")
		(sheetfile "peripherals.kicad_sch")
		(attr smd)
		(fp_line
			(start -15.85 -2.15)
			(end -12.5 -2.15)
			(stroke
				(width 0.15)
				(type solid)
			)
			(layer "F.SilkS")
		)
		(fp_line
			(start -15.85 2.7)
			(end -15.85 -2.15)
			(stroke
				(width 0.15)
				(type solid)
			)
			(layer "F.SilkS")
		)
		(fp_line
			(start -12.5 -2.976)
			(end 12.499 -2.976)
			(stroke
				(width 0.15)
				(type solid)
			)
			(layer "F.SilkS")
		)
		(fp_line
			(start -12.5 -2.15)
			(end -12.5 -2.976)
			(stroke
				(width 0.15)
				(type solid)
			)
			(layer "F.SilkS")
		)
		(fp_line
			(start 12.499 -2.15)
			(end 12.499 -2.976)
			(stroke
				(width 0.15)
				(type solid)
			)
			(layer "F.SilkS")
		)
		(fp_line
			(start 15.85 -2.15)
			(end 12.499 -2.15)
			(stroke
				(width 0.15)
				(type solid)
			)
			(layer "F.SilkS")
		)
		(fp_line
			(start 15.85 2.7)
			(end -15.85 2.7)
			(stroke
				(width 0.15)
				(type solid)
			)
			(layer "F.SilkS")
		)
		(fp_line
			(start 15.85 2.7)
			(end 15.85 -2.15)
			(stroke
				(width 0.15)
				(type solid)
			)
			(layer "F.SilkS")
		)
		(fp_circle
			(center -12.9 -2.9)
			(end -12.85 -2.85)
			(stroke
				(width 0.15)
				(type solid)
			)
			(fill yes)
			(layer "F.SilkS")
		)
		(fp_rect
			(start -16.2 -3.25)
			(end 16.2 3.55)
			(stroke
				(width 0.05)
				(type solid)
			)
			(fill no)
			(layer "F.CrtYd")
		)
		(fp_text user "Author: Antmicro"
			(at -16.2 6.9 0)
			(layer "F.Fab")
			(effects
				(font
					(size 0.7 0.7)
					(thickness 0.15)
				)
				(justify left bottom)
			)
		)
		(fp_text user "${REFERENCE}"
			(at -16.2 5.9 0)
			(layer "F.Fab")
			(effects
				(font
					(size 0.7 0.7)
					(thickness 0.15)
				)
				(justify left bottom)
			)
		)
		(fp_text user "License: Apache-2.0"
			(at -16.2 7.9 0)
			(layer "F.Fab")
			(effects
				(font
					(size 0.7 0.7)
					(thickness 0.15)
				)
				(justify left bottom)
			)
		)
		(pad "1" smd roundrect
			(at -12.25 -2.15)
			(size 0.3 1.2)
			(layers "F.Cu" "F.Mask" "F.Paste")
			(roundrect_rratio 0.25)
			(net 133 "unconnected-(J6-Pad1)")
			(pintype "passive+no_connect")
		)
		(pad "2" smd roundrect
			(at -11.75 -2.15)
			(size 0.3 1.2)
			(layers "F.Cu" "F.Mask" "F.Paste")
			(roundrect_rratio 0.25)
			(net 132 "unconnected-(J6-Pad2)")
			(pintype "passive+no_connect")
		)
		(pad "3" smd roundrect
			(at -11.25 -2.15)
			(size 0.3 1.2)
			(layers "F.Cu" "F.Mask" "F.Paste")
			(roundrect_rratio 0.25)
			(net 131 "unconnected-(J6-Pad3)")
			(pintype "passive+no_connect")
		)
		(pad "4" smd roundrect
			(at -10.75 -2.15)
			(size 0.3 1.2)
			(layers "F.Cu" "F.Mask" "F.Paste")
			(roundrect_rratio 0.25)
			(net 130 "unconnected-(J6-Pad4)")
			(pintype "passive+no_connect")
		)
		(pad "5" smd roundrect
			(at -10.25 -2.15)
			(size 0.3 1.2)
			(layers "F.Cu" "F.Mask" "F.Paste")
			(roundrect_rratio 0.25)
			(net 129 "unconnected-(J6-Pad5)")
			(pintype "passive+no_connect")
		)
		(pad "6" smd roundrect
			(at -9.75 -2.15)
			(size 0.3 1.2)
			(layers "F.Cu" "F.Mask" "F.Paste")
			(roundrect_rratio 0.25)
			(net 128 "unconnected-(J6-Pad6)")
			(pintype "passive+no_connect")
		)
		(pad "7" smd roundrect
			(at -9.25 -2.15)
			(size 0.3 1.2)
			(layers "F.Cu" "F.Mask" "F.Paste")
			(roundrect_rratio 0.25)
			(net 127 "unconnected-(J6-Pad7)")
			(pintype "passive+no_connect")
		)
		(pad "8" smd roundrect
			(at -8.75 -2.15)
			(size 0.3 1.2)
			(layers "F.Cu" "F.Mask" "F.Paste")
			(roundrect_rratio 0.25)
			(net 126 "unconnected-(J6-Pad8)")
			(pintype "passive+no_connect")
		)
		(pad "9" smd roundrect
			(at -8.25 -2.15)
			(size 0.3 1.2)
			(layers "F.Cu" "F.Mask" "F.Paste")
			(roundrect_rratio 0.25)
			(net 1 "GND")
			(pintype "passive")
		)
		(pad "10" smd roundrect
			(at -7.75 -2.15)
			(size 0.3 1.2)
			(layers "F.Cu" "F.Mask" "F.Paste")
			(roundrect_rratio 0.25)
			(net 125 "unconnected-(J6-Pad10)")
			(pintype "passive+no_connect")
		)
		(pad "11" smd roundrect
			(at -7.25 -2.15)
			(size 0.3 1.2)
			(layers "F.Cu" "F.Mask" "F.Paste")
			(roundrect_rratio 0.25)
			(net 124 "unconnected-(J6-Pad11)")
			(pintype "passive+no_connect")
		)
		(pad "12" smd roundrect
			(at -6.75 -2.15)
			(size 0.3 1.2)
			(layers "F.Cu" "F.Mask" "F.Paste")
			(roundrect_rratio 0.25)
			(net 1 "GND")
			(pintype "passive")
		)
		(pad "13" smd roundrect
			(at -6.25 -2.15)
			(size 0.3 1.2)
			(layers "F.Cu" "F.Mask" "F.Paste")
			(roundrect_rratio 0.25)
			(net 123 "unconnected-(J6-Pad13)")
			(pintype "passive+no_connect")
		)
		(pad "14" smd roundrect
			(at -5.75 -2.15)
			(size 0.3 1.2)
			(layers "F.Cu" "F.Mask" "F.Paste")
			(roundrect_rratio 0.25)
			(net 122 "unconnected-(J6-Pad14)")
			(pintype "passive+no_connect")
		)
		(pad "15" smd roundrect
			(at -5.25 -2.15)
			(size 0.3 1.2)
			(layers "F.Cu" "F.Mask" "F.Paste")
			(roundrect_rratio 0.25)
			(net 1 "GND")
			(pintype "passive")
		)
		(pad "16" smd roundrect
			(at -4.75 -2.15)
			(size 0.3 1.2)
			(layers "F.Cu" "F.Mask" "F.Paste")
			(roundrect_rratio 0.25)
			(net 121 "unconnected-(J6-Pad16)")
			(pintype "passive+no_connect")
		)
		(pad "17" smd roundrect
			(at -4.25 -2.15)
			(size 0.3 1.2)
			(layers "F.Cu" "F.Mask" "F.Paste")
			(roundrect_rratio 0.25)
			(net 120 "unconnected-(J6-Pad17)")
			(pintype "passive+no_connect")
		)
		(pad "18" smd roundrect
			(at -3.75 -2.15)
			(size 0.3 1.2)
			(layers "F.Cu" "F.Mask" "F.Paste")
			(roundrect_rratio 0.25)
			(net 1 "GND")
			(pintype "passive")
		)
		(pad "19" smd roundrect
			(at -3.25 -2.15)
			(size 0.3 1.2)
			(layers "F.Cu" "F.Mask" "F.Paste")
			(roundrect_rratio 0.25)
			(net 119 "/Peripherals/MIPI1_D3_N")
			(pintype "passive")
		)
		(pad "20" smd roundrect
			(at -2.75 -2.15)
			(size 0.3 1.2)
			(layers "F.Cu" "F.Mask" "F.Paste")
			(roundrect_rratio 0.25)
			(net 118 "/Peripherals/MIPI1_D3_P")
			(pintype "passive")
		)
		(pad "21" smd roundrect
			(at -2.25 -2.15)
			(size 0.3 1.2)
			(layers "F.Cu" "F.Mask" "F.Paste")
			(roundrect_rratio 0.25)
			(net 117 "/Peripherals/MIPI1_D2_N")
			(pintype "passive")
		)
		(pad "22" smd roundrect
			(at -1.75 -2.15)
			(size 0.3 1.2)
			(layers "F.Cu" "F.Mask" "F.Paste")
			(roundrect_rratio 0.25)
			(net 116 "/Peripherals/MIPI1_D2_P")
			(pintype "passive")
		)
		(pad "23" smd roundrect
			(at -1.25 -2.15)
			(size 0.3 1.2)
			(layers "F.Cu" "F.Mask" "F.Paste")
			(roundrect_rratio 0.25)
			(net 115 "/Peripherals/MIPI1_D1_N")
			(pintype "passive")
		)
		(pad "24" smd roundrect
			(at -0.75 -2.15)
			(size 0.3 1.2)
			(layers "F.Cu" "F.Mask" "F.Paste")
			(roundrect_rratio 0.25)
			(net 114 "/Peripherals/MIPI1_D1_P")
			(pintype "passive")
		)
		(pad "25" smd roundrect
			(at -0.25 -2.15)
			(size 0.3 1.2)
			(layers "F.Cu" "F.Mask" "F.Paste")
			(roundrect_rratio 0.25)
			(net 113 "/Peripherals/MIPI1_D0_N")
			(pintype "passive")
		)
		(pad "26" smd roundrect
			(at 0.248 -2.15)
			(size 0.3 1.2)
			(layers "F.Cu" "F.Mask" "F.Paste")
			(roundrect_rratio 0.25)
			(net 112 "/Peripherals/MIPI1_D0_P")
			(pintype "passive")
		)
		(pad "27" smd roundrect
			(at 0.748 -2.15)
			(size 0.3 1.2)
			(layers "F.Cu" "F.Mask" "F.Paste")
			(roundrect_rratio 0.25)
			(net 1 "GND")
			(pintype "passive")
		)
		(pad "28" smd roundrect
			(at 1.249 -2.15)
			(size 0.3 1.2)
			(layers "F.Cu" "F.Mask" "F.Paste")
			(roundrect_rratio 0.25)
			(net 111 "/Peripherals/MIPI1_CLK_N")
			(pintype "passive")
		)
		(pad "29" smd roundrect
			(at 1.749 -2.15)
			(size 0.3 1.2)
			(layers "F.Cu" "F.Mask" "F.Paste")
			(roundrect_rratio 0.25)
			(net 110 "/Peripherals/MIPI1_CLK_P")
			(pintype "passive")
		)
		(pad "30" smd roundrect
			(at 2.249 -2.15)
			(size 0.3 1.2)
			(layers "F.Cu" "F.Mask" "F.Paste")
			(roundrect_rratio 0.25)
			(net 1 "GND")
			(pintype "passive")
		)
		(pad "31" smd roundrect
			(at 2.749 -2.15)
			(size 0.3 1.2)
			(layers "F.Cu" "F.Mask" "F.Paste")
			(roundrect_rratio 0.25)
			(net 109 "unconnected-(J6-Pad31)")
			(pintype "passive+no_connect")
		)
		(pad "32" smd roundrect
			(at 3.249 -2.15)
			(size 0.3 1.2)
			(layers "F.Cu" "F.Mask" "F.Paste")
			(roundrect_rratio 0.25)
			(net 343 "Net-(J6-Pad32)")
			(pintype "passive")
		)
		(pad "33" smd roundrect
			(at 3.749 -2.15)
			(size 0.3 1.2)
			(layers "F.Cu" "F.Mask" "F.Paste")
			(roundrect_rratio 0.25)
			(net 344 "Net-(J6-Pad33)")
			(pintype "passive")
		)
		(pad "34" smd roundrect
			(at 4.248 -2.15)
			(size 0.3 1.2)
			(layers "F.Cu" "F.Mask" "F.Paste")
			(roundrect_rratio 0.25)
			(net 345 "Net-(J6-Pad34)")
			(pintype "passive")
		)
		(pad "35" smd roundrect
			(at 4.748 -2.15)
			(size 0.3 1.2)
			(layers "F.Cu" "F.Mask" "F.Paste")
			(roundrect_rratio 0.25)
			(net 105 "unconnected-(J6-Pad35)")
			(pintype "passive+no_connect")
		)
		(pad "36" smd roundrect
			(at 5.248 -2.15)
			(size 0.3 1.2)
			(layers "F.Cu" "F.Mask" "F.Paste")
			(roundrect_rratio 0.25)
			(net 104 "unconnected-(J6-Pad36)")
			(pintype "passive+no_connect")
		)
		(pad "37" smd roundrect
			(at 5.749 -2.15)
			(size 0.3 1.2)
			(layers "F.Cu" "F.Mask" "F.Paste")
			(roundrect_rratio 0.25)
			(net 103 "unconnected-(J6-Pad37)")
			(pintype "passive+no_connect")
		)
		(pad "38" smd roundrect
			(at 6.249 -2.15)
			(size 0.3 1.2)
			(layers "F.Cu" "F.Mask" "F.Paste")
			(roundrect_rratio 0.25)
			(net 102 "unconnected-(J6-Pad38)")
			(pintype "passive+no_connect")
		)
		(pad "39" smd roundrect
			(at 6.749 -2.15)
			(size 0.3 1.2)
			(layers "F.Cu" "F.Mask" "F.Paste")
			(roundrect_rratio 0.25)
			(net 323 "Net-(J6-Pad39)")
			(pintype "passive")
		)
		(pad "40" smd roundrect
			(at 7.249 -2.15)
			(size 0.3 1.2)
			(layers "F.Cu" "F.Mask" "F.Paste")
			(roundrect_rratio 0.25)
			(net 302 "Net-(J6-Pad40)")
			(pintype "passive")
		)
		(pad "41" smd roundrect
			(at 7.749 -2.15)
			(size 0.3 1.2)
			(layers "F.Cu" "F.Mask" "F.Paste")
			(roundrect_rratio 0.25)
			(net 346 "Net-(J6-Pad41)")
			(pintype "passive")
		)
		(pad "42" smd roundrect
			(at 8.249 -2.15)
			(size 0.3 1.2)
			(layers "F.Cu" "F.Mask" "F.Paste")
			(roundrect_rratio 0.25)
			(net 347 "Net-(J6-Pad42)")
			(pintype "passive")
		)
		(pad "43" smd roundrect
			(at 8.749 -2.15)
			(size 0.3 1.2)
			(layers "F.Cu" "F.Mask" "F.Paste")
			(roundrect_rratio 0.25)
			(net 98 "unconnected-(J6-Pad43)")
			(pintype "passive+no_connect")
		)
		(pad "44" smd roundrect
			(at 9.249 -2.15)
			(size 0.3 1.2)
			(layers "F.Cu" "F.Mask" "F.Paste")
			(roundrect_rratio 0.25)
			(net 97 "unconnected-(J6-Pad44)")
			(pintype "passive+no_connect")
		)
		(pad "45" smd roundrect
			(at 9.749 -2.15)
			(size 0.3 1.2)
			(layers "F.Cu" "F.Mask" "F.Paste")
			(roundrect_rratio 0.25)
			(net 96 "unconnected-(J6-Pad45)")
			(pintype "passive+no_connect")
		)
		(pad "46" smd roundrect
			(at 10.249 -2.15)
			(size 0.3 1.2)
			(layers "F.Cu" "F.Mask" "F.Paste")
			(roundrect_rratio 0.25)
			(net 95 "unconnected-(J6-Pad46)")
			(pintype "passive+no_connect")
		)
		(pad "47" smd roundrect
			(at 10.749 -2.15)
			(size 0.3 1.2)
			(layers "F.Cu" "F.Mask" "F.Paste")
			(roundrect_rratio 0.25)
			(net 18 "/Peripherals/FFC2_3V3")
			(pintype "passive")
		)
		(pad "48" smd roundrect
			(at 11.249 -2.15)
			(size 0.3 1.2)
			(layers "F.Cu" "F.Mask" "F.Paste")
			(roundrect_rratio 0.25)
			(net 18 "/Peripherals/FFC2_3V3")
			(pintype "passive")
		)
		(pad "49" smd roundrect
			(at 11.749 -2.15)
			(size 0.3 1.2)
			(layers "F.Cu" "F.Mask" "F.Paste")
			(roundrect_rratio 0.25)
			(net 19 "FFC2_5V")
			(pintype "passive")
		)
		(pad "50" smd roundrect
			(at 12.249 -2.15)
			(size 0.3 1.2)
			(layers "F.Cu" "F.Mask" "F.Paste")
			(roundrect_rratio 0.25)
			(net 19 "FFC2_5V")
			(pintype "passive")
		)
		(pad "MP1" smd roundrect
			(at -14.198 -0.3)
			(size 2.7 3)
			(layers "F.Cu" "F.Mask" "F.Paste")
			(roundrect_rratio 0.05)
			(net 1 "GND")
			(pinfunction "MP")
			(pintype "passive")
		)
		(pad "MP2" smd roundrect
			(at 14.198 -0.3)
			(size 2.7 3)
			(layers "F.Cu" "F.Mask" "F.Paste")
			(roundrect_rratio 0.05)
			(net 1 "GND")
			(pinfunction "MP")
			(pintype "passive")
		)
	)
	(footprint "antmicro-footprints:TP_SMD_0.75mm"
		(layer "F.Cu")
		(at 88.7 109.25)
		(property "Reference" "TP14"
			(at -2.07 1.39 0)
			(layer "F.SilkS")
			(effects
				(font
					(size 0.65 0.65)
					(thickness 0.15)
				)
				(justify left bottom)
			)
		)
		(property "Value" "TP_0.75mm_SMD"
			(at 0 1.2 0)
			(layer "F.Fab")
			(hide yes)
			(effects
				(font
					(size 0.7 0.7)
					(thickness 0.15)
				)
				(justify left bottom)
			)
		)
		(property "Description" "SMT test point"
			(at 0 0 0)
			(layer "F.Fab")
			(hide yes)
			(effects
				(font
					(size 1.27 1.27)
					(thickness 0.15)
				)
			)
		)
		(property "Author" "Antmicro"
			(at 0 0 0)
			(layer "F.Fab")
			(hide yes)
			(effects
				(font
					(size 1 1)
					(thickness 0.15)
				)
			)
		)
		(property "License" "Apache-2.0"
			(at 0 0 0)
			(layer "F.Fab")
			(hide yes)
			(effects
				(font
					(size 1 1)
					(thickness 0.15)
				)
			)
		)
		(property "MPN" ""
			(at 0 0 0)
			(layer "F.Fab")
			(hide yes)
			(effects
				(font
					(size 1 1)
					(thickness 0.15)
				)
			)
		)
		(property "Manufacturer" ""
			(at 0 0 0)
			(layer "F.Fab")
			(hide yes)
			(effects
				(font
					(size 1 1)
					(thickness 0.15)
				)
			)
		)
		(sheetname "/SDI/")
		(sheetfile "sdi.kicad_sch")
		(attr exclude_from_pos_files)
		(fp_circle
			(center 0 0)
			(end 0.475 0)
			(stroke
				(width 0.05)
				(type default)
			)
			(fill no)
			(layer "F.CrtYd")
		)
		(fp_text user "License: Apache-2.0"
			(at -0.4 5.101 0)
			(layer "F.Fab")
			(effects
				(font
					(size 0.7 0.7)
					(thickness 0.15)
				)
				(justify left bottom)
			)
		)
		(fp_text user "Author: Antmicro"
			(at -0.4 3.901 0)
			(layer "F.Fab")
			(effects
				(font
					(size 0.7 0.7)
					(thickness 0.15)
				)
				(justify left bottom)
			)
		)
		(fp_text user "${REFERENCE}"
			(at -0.4 2.7 0)
			(layer "F.Fab")
			(effects
				(font
					(size 0.7 0.7)
					(thickness 0.15)
				)
				(justify left bottom)
			)
		)
		(pad "1" smd circle
			(at 0 0)
			(size 0.75 0.75)
			(layers "F.Cu" "F.Mask")
			(net 378 "Net-(U16-~{OSP})")
			(pinfunction "1")
			(pintype "passive")
		)
	)
)
